H
G
F
E
D
C
B
A
H
G
F
E
D
C
B
A
1 2 3 4 5 6 7 8 9 10 11
1 2 3 4 5 6 7 8 9 10 11
DRAWING NO.
SCALE DWG
DO NOT 
MODEL NAME
Wiwynn CorporationAPPD
CKD
DSN
DRN
SHEET
SIGNREV DESCRIPTION DATEMATERIAL
FINISH
OF
DIM IN  mm
185.00
0.00
4.13
12.13
76.70
124.13
172.88
180.88
10.00
0.00
17.20
9.60
17.60
72.70
80.70
104.25
112.25
135.80
143.80
167.35
175.35
6-5.00
(NPTH)2.90
(NPTH)2.90
4- (PAD)(NO TRACE AT ALL LAYERS)6.00
4- ((PTH))2.55
4- (PAD)(NO TRACE AT ALL LAYERS)6.00
40.65
57.65
18.20
1.00
BryceCanyon BryceCanyon LED BOARD 2L
CD  
Jess Wang 2/9
2017
Jess Wang 2/9
2017
IT150G / NPG150N T=1.0mm 
1 1 Lenny Kao
Lenny Kao
2/9
2017
2/9
2017
16347-SC VERSION A 2017-02-09